# T6G (Grand Teton) — schematic netlist excerpt (pin names and nets, part order shuffled) for the footprints in the layout excerpt that follows; sources: Cadence DE-HDL packaged netlist, KiCad conversion of 04192023_DAF0TMB3IC0_F0TG_MB_C_brd_V02_OCP.brd

R708  Q_RES  33 5% CHIP  pkg 0402LF  page 81 : A = FM_HDT_HDR_PWROK ; B = HDT_HDR_PWROK
C1042  Q_CAP  100NF 50V 10% X7R  pkg C0402  page 188 : A = P5V_AUX ; B = GND

(kicad_pcb
	(version 20260206)
	(generator "pcbnew")
	(generator_version "10.0")
	(general
		(thickness 1.6)
		(legacy_teardrops no)
	)
	(paper "A4")
	(title_block
		(title "04192023_DAF0TMB3IC0_F0TG_MB_C_brd_V02_OCP.brd")
		(comment 1 "Grand Teton / footprints 1963-1964 of 8354")
	)
	(layers
		(0 "F.Cu" signal "TOP")
		(4 "In1.Cu" signal "GND")
		(6 "In2.Cu" signal "IN1")
		(8 "In3.Cu" signal "GND1")
		(10 "In4.Cu" signal "IN2")
		(12 "In5.Cu" signal "GND2")
		(14 "In6.Cu" signal "IN3")
		(16 "In7.Cu" signal "GND3")
		(18 "In8.Cu" signal "VCC")
		(20 "In9.Cu" signal "VCC1")
		(22 "In10.Cu" signal "GND4")
		(24 "In11.Cu" signal "IN4")
		(26 "In12.Cu" signal "GND5")
		(28 "In13.Cu" signal "IN5")
		(30 "In14.Cu" signal "GND6")
		(32 "In15.Cu" signal "IN6")
		(34 "In16.Cu" signal "GND7")
		(2 "B.Cu" signal "BOTTOM")
		(9 "F.Adhes" user "F.Adhesive")
		(11 "B.Adhes" user "B.Adhesive")
		(13 "F.Paste" user "Package Geometry/Pastemask Top")
		(15 "B.Paste" user "Package Geometry/Pastemask Bottom")
		(5 "F.SilkS" user "Ref Des/Silkscreen Top")
		(7 "B.SilkS" user "Ref Des/Silkscreen Bottom")
		(1 "F.Mask" user "Board Geometry/Soldermask Top")
		(3 "B.Mask" user "Board Geometry/Soldermask Bottom")
		(17 "Dwgs.User" user "User.Drawings")
		(19 "Cmts.User" user "User.Comments")
		(21 "Eco1.User" user "User.Eco1")
		(23 "Eco2.User" user "User.Eco2")
		(25 "Edge.Cuts" user "Board Geometry/Outline")
		(27 "Margin" user)
		(31 "F.CrtYd" user "Package Geometry/Place Bound Top")
		(29 "B.CrtYd" user "Package Geometry/Place Bound Bottom")
		(35 "F.Fab" user "Ref Des/Assembly Top")
		(33 "B.Fab" user "Ref Des/Assembly Bottom")
	)
	(footprint ""
		(layer "F.Cu")
		(at 190.119 -133.568948 90)
		(property "Reference" "R708"
			(at 0 0 90)
			(layer "F.SilkS")
			(hide yes)
			(effects
				(font
					(size 1.27 1.27)
				)
			)
		)
		(property "Value" ""
			(at 0 0 90)
			(layer "F.Fab")
			(effects
				(font
					(size 1.27 1.27)
				)
			)
		)
		(duplicate_pad_numbers_are_jumpers no)
		(fp_line
			(start 0.7874 -0.4064)
			(end 0.7874 0.4064)
			(stroke
				(width 0.1524)
				(type default)
			)
			(layer "F.SilkS")
		)
		(fp_line
			(start -0.7874 -0.4064)
			(end 0.7874 -0.4064)
			(stroke
				(width 0.1524)
				(type default)
			)
			(layer "F.SilkS")
		)
		(fp_line
			(start 0.7874 0.4064)
			(end -0.7874 0.4064)
			(stroke
				(width 0.1524)
				(type default)
			)
			(layer "F.SilkS")
		)
		(fp_line
			(start -0.7874 0.4064)
			(end -0.7874 -0.4064)
			(stroke
				(width 0.1524)
				(type default)
			)
			(layer "F.SilkS")
		)
		(fp_line
			(start -0.12065 -0.305054)
			(end -0.12065 -0.2794)
			(stroke
				(width 0.1)
				(type default)
			)
			(layer "F.Fab")
		)
		(fp_line
			(start -0.67945 -0.305054)
			(end -0.12065 -0.305054)
			(stroke
				(width 0.1)
				(type default)
			)
			(layer "F.Fab")
		)
		(fp_line
			(start 0.67945 -0.3048)
			(end 0.67945 0.3048)
			(stroke
				(width 0.1)
				(type default)
			)
			(layer "F.Fab")
		)
		(fp_line
			(start 0.12065 -0.3048)
			(end 0.67945 -0.3048)
			(stroke
				(width 0.1)
				(type default)
			)
			(layer "F.Fab")
		)
		(fp_line
			(start 0.12065 -0.2794)
			(end 0.12065 -0.3048)
			(stroke
				(width 0.1)
				(type default)
			)
			(layer "F.Fab")
		)
		(fp_line
			(start -0.12065 -0.2794)
			(end 0.12065 -0.2794)
			(stroke
				(width 0.1)
				(type default)
			)
			(layer "F.Fab")
		)
		(fp_line
			(start 0.120396 0.2794)
			(end -0.12065 0.2794)
			(stroke
				(width 0.1)
				(type default)
			)
			(layer "F.Fab")
		)
		(fp_line
			(start -0.12065 0.2794)
			(end -0.12065 0.3048)
			(stroke
				(width 0.1)
				(type default)
			)
			(layer "F.Fab")
		)
		(fp_line
			(start 0.67945 0.3048)
			(end 0.120396 0.3048)
			(stroke
				(width 0.1)
				(type default)
			)
			(layer "F.Fab")
		)
		(fp_line
			(start 0.120396 0.3048)
			(end 0.120396 0.2794)
			(stroke
				(width 0.1)
				(type default)
			)
			(layer "F.Fab")
		)
		(fp_line
			(start -0.12065 0.3048)
			(end -0.67945 0.3048)
			(stroke
				(width 0.1)
				(type default)
			)
			(layer "F.Fab")
		)
		(fp_line
			(start -0.67945 0.3048)
			(end -0.67945 -0.305054)
			(stroke
				(width 0.1)
				(type default)
			)
			(layer "F.Fab")
		)
		(pad "1" smd circle
			(at -0.40005 0 90)
			(size 0 0)
			(layers "F.Cu" "F.Mask" "F.Paste")
			(net "FM_HDT_HDR_PWROK")
		)
		(pad "2" smd circle
			(at 0.40005 0 90)
			(size 0 0)
			(layers "F.Cu" "F.Mask" "F.Paste")
			(net "HDT_HDR_PWROK")
		)
	)
	(footprint ""
		(layer "F.Cu")
		(at 402.356066 -143.029432 -90)
		(property "Reference" "C1042"
			(at 0 0 270)
			(layer "F.SilkS")
			(hide yes)
			(effects
				(font
					(size 1.27 1.27)
				)
			)
		)
		(property "Value" ""
			(at 0 0 270)
			(layer "F.Fab")
			(effects
				(font
					(size 1.27 1.27)
				)
			)
		)
		(duplicate_pad_numbers_are_jumpers no)
		(fp_line
			(start -0.7874 0.4064)
			(end -0.7874 -0.4064)
			(stroke
				(width 0.1524)
				(type default)
			)
			(layer "F.SilkS")
		)
		(fp_line
			(start 0.7874 0.4064)
			(end -0.7874 0.4064)
			(stroke
				(width 0.1524)
				(type default)
			)
			(layer "F.SilkS")
		)
		(fp_line
			(start -0.7874 -0.4064)
			(end 0.7874 -0.4064)
			(stroke
				(width 0.1524)
				(type default)
			)
			(layer "F.SilkS")
		)
		(fp_line
			(start 0.7874 -0.4064)
			(end 0.7874 0.4064)
			(stroke
				(width 0.1524)
				(type default)
			)
			(layer "F.SilkS")
		)
		(fp_line
			(start -0.67945 0.3048)
			(end -0.67945 -0.305054)
			(stroke
				(width 0.1)
				(type default)
			)
			(layer "F.Fab")
		)
		(fp_line
			(start -0.12065 0.3048)
			(end -0.67945 0.3048)
			(stroke
				(width 0.1)
				(type default)
			)
			(layer "F.Fab")
		)
		(fp_line
			(start 0.120396 0.3048)
			(end 0.120396 0.2794)
			(stroke
				(width 0.1)
				(type default)
			)
			(layer "F.Fab")
		)
		(fp_line
			(start 0.67945 0.3048)
			(end 0.120396 0.3048)
			(stroke
				(width 0.1)
				(type default)
			)
			(layer "F.Fab")
		)
		(fp_line
			(start -0.12065 0.2794)
			(end -0.12065 0.3048)
			(stroke
				(width 0.1)
				(type default)
			)
			(layer "F.Fab")
		)
		(fp_line
			(start 0.120396 0.2794)
			(end -0.12065 0.2794)
			(stroke
				(width 0.1)
				(type default)
			)
			(layer "F.Fab")
		)
		(fp_line
			(start -0.12065 -0.2794)
			(end 0.12065 -0.2794)
			(stroke
				(width 0.1)
				(type default)
			)
			(layer "F.Fab")
		)
		(fp_line
			(start 0.12065 -0.2794)
			(end 0.12065 -0.3048)
			(stroke
				(width 0.1)
				(type default)
			)
			(layer "F.Fab")
		)
		(fp_line
			(start 0.12065 -0.3048)
			(end 0.67945 -0.3048)
			(stroke
				(width 0.1)
				(type default)
			)
			(layer "F.Fab")
		)
		(fp_line
			(start 0.67945 -0.3048)
			(end 0.67945 0.3048)
			(stroke
				(width 0.1)
				(type default)
			)
			(layer "F.Fab")
		)
		(fp_line
			(start -0.67945 -0.305054)
			(end -0.12065 -0.305054)
			(stroke
				(width 0.1)
				(type default)
			)
			(layer "F.Fab")
		)
		(fp_line
			(start -0.12065 -0.305054)
			(end -0.12065 -0.2794)
			(stroke
				(width 0.1)
				(type default)
			)
			(layer "F.Fab")
		)
		(pad "1" smd circle
			(at -0.40005 0 270)
			(size 0 0)
			(layers "F.Cu" "F.Mask" "F.Paste")
			(net "P5V_AUX")
		)
		(pad "2" smd circle
			(at 0.40005 0 270)
			(size 0 0)
			(layers "F.Cu" "F.Mask" "F.Paste")
			(net "GND")
		)
	)
)
